(kicad_pcb
	(version 20241229)
	(generator "pcbnew")
	(generator_version "9.0")
	(general
		(thickness 1.61)
		(legacy_teardrops no)
	)
	(paper "A3")
	(title_block
		(title "SO-DIMM DDR5 Tester")
		(date "2025-11-26")
		(rev "1.3.0")
		(comment 9 "footprints 382-388 of 627")
	)
	(layers
		(0 "F.Cu" signal)
		(4 "In1.Cu" power)
		(6 "In2.Cu" mixed)
		(8 "In3.Cu" power)
		(10 "In4.Cu" mixed)
		(12 "In5.Cu" power)
		(14 "In6.Cu" mixed)
		(16 "In7.Cu" power)
		(18 "In8.Cu" power)
		(20 "In9.Cu" mixed)
		(22 "In10.Cu" power)
		(2 "B.Cu" signal)
		(9 "F.Adhes" user "F.Adhesive")
		(11 "B.Adhes" user "B.Adhesive")
		(13 "F.Paste" user)
		(15 "B.Paste" user)
		(5 "F.SilkS" user "F.Silkscreen")
		(7 "B.SilkS" user "B.Silkscreen")
		(1 "F.Mask" user)
		(3 "B.Mask" user)
		(17 "Dwgs.User" user "User.Drawings")
		(19 "Cmts.User" user "User.Comments")
		(21 "Eco1.User" user "User.Eco1")
		(23 "Eco2.User" user "User.Eco2")
		(25 "Edge.Cuts" user)
		(27 "Margin" user)
		(31 "F.CrtYd" user "F.Courtyard")
		(29 "B.CrtYd" user "B.Courtyard")
		(35 "F.Fab" user)
		(33 "B.Fab" user)
	)
	(footprint "antmicro-footprints:R_0402_1005Metric"
		(layer "B.Cu")
		(at 159.7005 180.676001)
		(descr "Resistor SMD 0402")
		(tags "resistor SMD 0402")
		(property "Reference" "R15"
			(at -1.122484 0.772697 180)
			(layer "B.SilkS")
			(hide yes)
			(effects
				(font
					(size 0.7 0.7)
					(thickness 0.15)
				)
				(justify left bottom mirror)
			)
		)
		(property "Value" "R_10k_0402"
			(at -1.011843 -1.772047 180)
			(layer "B.Fab")
			(effects
				(font
					(size 0.7 0.7)
					(thickness 0.15)
				)
				(justify left bottom mirror)
			)
		)
		(property "Datasheet" "https://www.bourns.com/docs/product-datasheets/cr.pdf"
			(at 0 0 0)
			(layer "F.Fab")
			(hide yes)
			(effects
				(font
					(size 1.27 1.27)
					(thickness 0.15)
				)
			)
		)
		(property "Author" "Antmicro"
			(at 0 0 0)
			(layer "B.Fab")
			(hide yes)
			(effects
				(font
					(size 1 1)
					(thickness 0.15)
				)
				(justify mirror)
			)
		)
		(property "License" "Apache-2.0"
			(at 0 0 0)
			(layer "B.Fab")
			(hide yes)
			(effects
				(font
					(size 1 1)
					(thickness 0.15)
				)
				(justify mirror)
			)
		)
		(property "MPN" "CR0402-FX-1002GLF"
			(at 0 0 0)
			(layer "B.Fab")
			(hide yes)
			(effects
				(font
					(size 1 1)
					(thickness 0.15)
				)
				(justify mirror)
			)
		)
		(property "Manufacturer" "Bourns"
			(at 0 0 0)
			(layer "B.Fab")
			(hide yes)
			(effects
				(font
					(size 1 1)
					(thickness 0.15)
				)
				(justify mirror)
			)
		)
		(property "Tolerance" "1%"
			(at 0 0 0)
			(layer "B.Fab")
			(hide yes)
			(effects
				(font
					(size 1 1)
					(thickness 0.15)
				)
				(justify mirror)
			)
		)
		(property "Val" "10k"
			(at 0 0 0)
			(layer "B.Fab")
			(hide yes)
			(effects
				(font
					(size 1 1)
					(thickness 0.15)
				)
				(justify mirror)
			)
		)
		(sheetname "/FPGA Config/")
		(sheetfile "fpga-config.kicad_sch")
		(attr smd)
		(fp_rect
			(start -0.93 0.47)
			(end 0.93 -0.47)
			(stroke
				(width 0.05)
				(type solid)
			)
			(fill no)
			(layer "B.CrtYd")
		)
		(fp_rect
			(start -0.5 0.25)
			(end 0.5 -0.25)
			(stroke
				(width 0.15)
				(type solid)
			)
			(fill no)
			(layer "B.Fab")
		)
		(pad "1" smd roundrect
			(at -0.485 0)
			(size 0.59 0.64)
			(layers "B.Cu" "B.Mask" "B.Paste")
			(roundrect_rratio 0.25)
			(net 632 "/FPGA Config/MODE1")
			(pintype "passive")
		)
		(pad "2" smd roundrect
			(at 0.485 0)
			(size 0.59 0.64)
			(layers "B.Cu" "B.Mask" "B.Paste")
			(roundrect_rratio 0.25)
			(net 200 "+3V3")
			(pintype "passive")
		)
	)
	(footprint "antmicro-footprints:TP_SMD_1mm"
		(layer "B.Cu")
		(at 165.25 199.15 180)
		(property "Reference" "TP27"
			(at 0 0.731898 0)
			(layer "B.SilkS")
			(hide yes)
			(effects
				(font
					(size 0.7 0.7)
					(thickness 0.15)
				)
				(justify left bottom mirror)
			)
		)
		(property "Value" "TP_1mm_SMD"
			(at 0 -1.4 0)
			(layer "B.Fab")
			(effects
				(font
					(size 0.7 0.7)
					(thickness 0.15)
				)
				(justify left bottom mirror)
			)
		)
		(property "MPN" ""
			(at 0 0 0)
			(unlocked yes)
			(layer "B.Fab")
			(hide yes)
			(effects
				(font
					(size 1 1)
					(thickness 0.15)
				)
				(justify mirror)
			)
		)
		(property "Manufacturer" ""
			(at 0 0 0)
			(unlocked yes)
			(layer "B.Fab")
			(hide yes)
			(effects
				(font
					(size 1 1)
					(thickness 0.15)
				)
				(justify mirror)
			)
		)
		(property "Author" "Antmicro"
			(at 0 0 0)
			(unlocked yes)
			(layer "B.Fab")
			(hide yes)
			(effects
				(font
					(size 1 1)
					(thickness 0.15)
				)
				(justify mirror)
			)
		)
		(property "License" "Apache-2.0"
			(at 0 0 0)
			(unlocked yes)
			(layer "B.Fab")
			(hide yes)
			(effects
				(font
					(size 1 1)
					(thickness 0.15)
				)
				(justify mirror)
			)
		)
		(sheetname "/Supply/")
		(sheetfile "supply.kicad_sch")
		(attr exclude_from_pos_files)
		(fp_circle
			(center 0 0)
			(end 0.6 0)
			(stroke
				(width 0.05)
				(type default)
			)
			(fill no)
			(layer "B.CrtYd")
		)
		(fp_text user "License: Apache-2.0"
			(at -0.5 -5.2 0)
			(layer "B.Fab")
			(effects
				(font
					(size 0.7 0.7)
					(thickness 0.15)
				)
				(justify left bottom mirror)
			)
		)
		(fp_text user "Author: Antmicro"
			(at -0.5 -4 0)
			(layer "B.Fab")
			(effects
				(font
					(size 0.7 0.7)
					(thickness 0.15)
				)
				(justify left bottom mirror)
			)
		)
		(fp_text user "${REFERENCE}"
			(at -0.5 -2.8 0)
			(layer "B.Fab")
			(effects
				(font
					(size 0.7 0.7)
					(thickness 0.15)
				)
				(justify left bottom mirror)
			)
		)
		(pad "1" smd circle
			(at 0 0 180)
			(size 1 1)
			(layers "B.Cu" "B.Mask")
			(net 227 "+1V0")
			(pinfunction "1")
			(pintype "passive")
		)
	)
	(footprint "antmicro-footprints:C_0402_1005Metric"
		(layer "B.Cu")
		(at 143.375501 172.801 -90)
		(descr "Capacitor SMD 0402 (1005 Metric), square (rectangular) end terminal, IPC_7351 nominal, (Body size source: IPC-SM-782 page 76, https://www.pcb-3d.com/wordpress/wp-content/uploads/ipc-sm-782a_amendment_1_and_2.pdf)")
		(tags "capacitor 0402")
		(property "Reference" "C72"
			(at 0 1.17 90)
			(layer "B.SilkS")
			(hide yes)
			(effects
				(font
					(size 0.7 0.7)
					(thickness 0.15)
				)
				(justify left bottom mirror)
			)
		)
		(property "Value" "C_100n_0402"
			(at 0 -1.169 90)
			(layer "B.Fab")
			(effects
				(font
					(size 0.7 0.7)
					(thickness 0.15)
				)
				(justify left bottom mirror)
			)
		)
		(property "Datasheet" "https://www.murata.com/products/productdetail?partno=GRM155R61H104KE14%23"
			(at 0 0 270)
			(layer "F.Fab")
			(hide yes)
			(effects
				(font
					(size 1.27 1.27)
					(thickness 0.15)
				)
			)
		)
		(property "Author" "Antmicro"
			(at -29.425499 316.176501 0)
			(layer "B.Fab")
			(hide yes)
			(effects
				(font
					(size 1 1)
					(thickness 0.15)
				)
				(justify mirror)
			)
		)
		(property "Dielectric" "X5R"
			(at -29.425499 316.176501 0)
			(layer "B.Fab")
			(hide yes)
			(effects
				(font
					(size 1 1)
					(thickness 0.15)
				)
				(justify mirror)
			)
		)
		(property "License" "Apache-2.0"
			(at -29.425499 316.176501 0)
			(layer "B.Fab")
			(hide yes)
			(effects
				(font
					(size 1 1)
					(thickness 0.15)
				)
				(justify mirror)
			)
		)
		(property "MPN" "GRM155R61H104KE14D"
			(at -29.425499 316.176501 0)
			(layer "B.Fab")
			(hide yes)
			(effects
				(font
					(size 1 1)
					(thickness 0.15)
				)
				(justify mirror)
			)
		)
		(property "Manufacturer" "Murata"
			(at -29.425499 316.176501 0)
			(layer "B.Fab")
			(hide yes)
			(effects
				(font
					(size 1 1)
					(thickness 0.15)
				)
				(justify mirror)
			)
		)
		(property "Val" "100n"
			(at -29.425499 316.176501 0)
			(layer "B.Fab")
			(hide yes)
			(effects
				(font
					(size 1 1)
					(thickness 0.15)
				)
				(justify mirror)
			)
		)
		(property "Voltage" "50V"
			(at -29.425499 316.176501 0)
			(layer "B.Fab")
			(hide yes)
			(effects
				(font
					(size 1 1)
					(thickness 0.15)
				)
				(justify mirror)
			)
		)
		(sheetname "/FPGA power/")
		(sheetfile "fpga-power.kicad_sch")
		(attr smd)
		(fp_rect
			(start -0.9656 0.4572)
			(end 0.9652 -0.4828)
			(stroke
				(width 0.05)
				(type solid)
			)
			(fill no)
			(layer "B.CrtYd")
		)
		(fp_line
			(start -0.5 0.25)
			(end 0.498 0.25)
			(stroke
				(width 0.15)
				(type solid)
			)
			(layer "B.Fab")
		)
		(fp_line
			(start 0.498 0.25)
			(end 0.498 -0.248)
			(stroke
				(width 0.15)
				(type solid)
			)
			(layer "B.Fab")
		)
		(fp_line
			(start -0.5 -0.248)
			(end -0.5 0.25)
			(stroke
				(width 0.15)
				(type solid)
			)
			(layer "B.Fab")
		)
		(fp_line
			(start 0.498 -0.248)
			(end -0.5 -0.248)
			(stroke
				(width 0.15)
				(type solid)
			)
			(layer "B.Fab")
		)
		(pad "1" smd roundrect
			(at -0.5 0 180)
			(size 0.6 0.6)
			(layers "B.Cu" "B.Mask" "B.Paste")
			(roundrect_rratio 0.25)
			(net 1 "GND")
			(pintype "passive")
		)
		(pad "2" smd roundrect
			(at 0.498 0 270)
			(size 0.6 0.6)
			(layers "B.Cu" "B.Mask" "B.Paste")
			(roundrect_rratio 0.25)
			(net 188 "+1V8")
			(pintype "passive")
		)
	)
	(footprint "antmicro-footprints:R_0402_1005Metric"
		(layer "B.Cu")
		(at 146.05 142.4 90)
		(descr "Resistor SMD 0402")
		(tags "resistor SMD 0402")
		(property "Reference" "R31"
			(at 3 0.3 270)
			(layer "B.SilkS")
			(effects
				(font
					(size 0.7 0.7)
					(thickness 0.15)
				)
				(justify left bottom mirror)
			)
		)
		(property "Value" "R_0R_0402"
			(at -1.011843 -1.772047 270)
			(layer "B.Fab")
			(effects
				(font
					(size 0.7 0.7)
					(thickness 0.15)
				)
				(justify left bottom mirror)
			)
		)
		(property "Datasheet" "https://industrial.panasonic.com/cdbs/www-data/pdf/RDA0000/AOA0000C301.pdf"
			(at 0 0 90)
			(layer "F.Fab")
			(hide yes)
			(effects
				(font
					(size 1.27 1.27)
					(thickness 0.15)
				)
			)
		)
		(property "Author" "Antmicro"
			(at 288.45 -3.65 0)
			(layer "B.Fab")
			(hide yes)
			(effects
				(font
					(size 1 1)
					(thickness 0.15)
				)
				(justify mirror)
			)
		)
		(property "Current" "1A"
			(at 288.45 -3.65 0)
			(layer "B.Fab")
			(hide yes)
			(effects
				(font
					(size 1 1)
					(thickness 0.15)
				)
				(justify mirror)
			)
		)
		(property "License" "Apache-2.0"
			(at 288.45 -3.65 0)
			(layer "B.Fab")
			(hide yes)
			(effects
				(font
					(size 1 1)
					(thickness 0.15)
				)
				(justify mirror)
			)
		)
		(property "MPN" "ERJ2GE0R00X"
			(at 288.45 -3.65 0)
			(layer "B.Fab")
			(hide yes)
			(effects
				(font
					(size 1 1)
					(thickness 0.15)
				)
				(justify mirror)
			)
		)
		(property "Manufacturer" "Panasonic"
			(at 288.45 -3.65 0)
			(layer "B.Fab")
			(hide yes)
			(effects
				(font
					(size 1 1)
					(thickness 0.15)
				)
				(justify mirror)
			)
		)
		(property "Tolerance" ""
			(at 288.45 -3.65 0)
			(layer "B.Fab")
			(hide yes)
			(effects
				(font
					(size 1 1)
					(thickness 0.15)
				)
				(justify mirror)
			)
		)
		(property "Val" "0R"
			(at 288.45 -3.65 0)
			(layer "B.Fab")
			(hide yes)
			(effects
				(font
					(size 1 1)
					(thickness 0.15)
				)
				(justify mirror)
			)
		)
		(sheetname "/DDR5 SODIMM/")
		(sheetfile "ddr5-sodimm.kicad_sch")
		(attr smd)
		(fp_rect
			(start -0.93 0.47)
			(end 0.93 -0.47)
			(stroke
				(width 0.05)
				(type solid)
			)
			(fill no)
			(layer "B.CrtYd")
		)
		(fp_rect
			(start -0.5 0.25)
			(end 0.5 -0.25)
			(stroke
				(width 0.15)
				(type solid)
			)
			(fill no)
			(layer "B.Fab")
		)
		(pad "1" smd roundrect
			(at -0.485 0 90)
			(size 0.59 0.64)
			(layers "B.Cu" "B.Mask" "B.Paste")
			(roundrect_rratio 0.25)
			(net 636 "/DDR5 SODIMM/Control.PWR_GOOD")
			(pintype "passive")
		)
		(pad "2" smd roundrect
			(at 0.485 0 90)
			(size 0.59 0.64)
			(layers "B.Cu" "B.Mask" "B.Paste")
			(roundrect_rratio 0.25)
			(net 313 "Net-(J2C-PWR_GOOD)")
			(pintype "passive")
		)
	)
	(footprint "antmicro-footprints:C_0402_1005Metric"
		(layer "B.Cu")
		(at 143.375001 177.8005 90)
		(descr "Capacitor SMD 0402 (1005 Metric), square (rectangular) end terminal, IPC_7351 nominal, (Body size source: IPC-SM-782 page 76, https://www.pcb-3d.com/wordpress/wp-content/uploads/ipc-sm-782a_amendment_1_and_2.pdf)")
		(tags "capacitor 0402")
		(property "Reference" "C88"
			(at 0 1.17 270)
			(layer "B.SilkS")
			(hide yes)
			(effects
				(font
					(size 0.7 0.7)
					(thickness 0.15)
				)
				(justify left bottom mirror)
			)
		)
		(property "Value" "C_100n_0402"
			(at 0 -1.169 270)
			(layer "B.Fab")
			(effects
				(font
					(size 0.7 0.7)
					(thickness 0.15)
				)
				(justify left bottom mirror)
			)
		)
		(property "Datasheet" "https://www.murata.com/products/productdetail?partno=GRM155R61H104KE14%23"
			(at 0 0 90)
			(layer "F.Fab")
			(hide yes)
			(effects
				(font
					(size 1.27 1.27)
					(thickness 0.15)
				)
			)
		)
		(property "Author" "Antmicro"
			(at 321.175501 34.425499 0)
			(layer "B.Fab")
			(hide yes)
			(effects
				(font
					(size 1 1)
					(thickness 0.15)
				)
				(justify mirror)
			)
		)
		(property "Dielectric" "X5R"
			(at 321.175501 34.425499 0)
			(layer "B.Fab")
			(hide yes)
			(effects
				(font
					(size 1 1)
					(thickness 0.15)
				)
				(justify mirror)
			)
		)
		(property "License" "Apache-2.0"
			(at 321.175501 34.425499 0)
			(layer "B.Fab")
			(hide yes)
			(effects
				(font
					(size 1 1)
					(thickness 0.15)
				)
				(justify mirror)
			)
		)
		(property "MPN" "GRM155R61H104KE14D"
			(at 321.175501 34.425499 0)
			(layer "B.Fab")
			(hide yes)
			(effects
				(font
					(size 1 1)
					(thickness 0.15)
				)
				(justify mirror)
			)
		)
		(property "Manufacturer" "Murata"
			(at 321.175501 34.425499 0)
			(layer "B.Fab")
			(hide yes)
			(effects
				(font
					(size 1 1)
					(thickness 0.15)
				)
				(justify mirror)
			)
		)
		(property "Val" "100n"
			(at 321.175501 34.425499 0)
			(layer "B.Fab")
			(hide yes)
			(effects
				(font
					(size 1 1)
					(thickness 0.15)
				)
				(justify mirror)
			)
		)
		(property "Voltage" "50V"
			(at 321.175501 34.425499 0)
			(layer "B.Fab")
			(hide yes)
			(effects
				(font
					(size 1 1)
					(thickness 0.15)
				)
				(justify mirror)
			)
		)
		(sheetname "/FPGA power/")
		(sheetfile "fpga-power.kicad_sch")
		(attr smd)
		(fp_rect
			(start -0.9656 0.4572)
			(end 0.9652 -0.4828)
			(stroke
				(width 0.05)
				(type solid)
			)
			(fill no)
			(layer "B.CrtYd")
		)
		(fp_line
			(start 0.498 -0.248)
			(end -0.5 -0.248)
			(stroke
				(width 0.15)
				(type solid)
			)
			(layer "B.Fab")
		)
		(fp_line
			(start -0.5 -0.248)
			(end -0.5 0.25)
			(stroke
				(width 0.15)
				(type solid)
			)
			(layer "B.Fab")
		)
		(fp_line
			(start 0.498 0.25)
			(end 0.498 -0.248)
			(stroke
				(width 0.15)
				(type solid)
			)
			(layer "B.Fab")
		)
		(fp_line
			(start -0.5 0.25)
			(end 0.498 0.25)
			(stroke
				(width 0.15)
				(type solid)
			)
			(layer "B.Fab")
		)
		(pad "1" smd roundrect
			(at -0.5 0)
			(size 0.6 0.6)
			(layers "B.Cu" "B.Mask" "B.Paste")
			(roundrect_rratio 0.25)
			(net 1 "GND")
			(pintype "passive")
		)
		(pad "2" smd roundrect
			(at 0.498 0 90)
			(size 0.6 0.6)
			(layers "B.Cu" "B.Mask" "B.Paste")
			(roundrect_rratio 0.25)
			(net 227 "+1V0")
			(pintype "passive")
		)
	)
	(footprint "antmicro-footprints:R_0402_1005Metric"
		(layer "B.Cu")
		(at 125 201.825 180)
		(descr "Resistor SMD 0402")
		(tags "resistor SMD 0402")
		(property "Reference" "R192"
			(at 1.1 -0.275 0)
			(layer "B.SilkS")
			(effects
				(font
					(size 0.7 0.7)
					(thickness 0.15)
				)
				(justify left bottom mirror)
			)
		)
		(property "Value" "R_10k_0402"
			(at -1.011843 -1.772047 0)
			(layer "B.Fab")
			(effects
				(font
					(size 0.7 0.7)
					(thickness 0.15)
				)
				(justify left bottom mirror)
			)
		)
		(property "Datasheet" "https://www.bourns.com/docs/product-datasheets/cr.pdf"
			(at 0 0 180)
			(layer "F.Fab")
			(hide yes)
			(effects
				(font
					(size 1.27 1.27)
					(thickness 0.15)
				)
			)
		)
		(property "Author" "Antmicro"
			(at 250 403.65 0)
			(layer "B.Fab")
			(hide yes)
			(effects
				(font
					(size 1 1)
					(thickness 0.15)
				)
				(justify mirror)
			)
		)
		(property "License" "Apache-2.0"
			(at 250 403.65 0)
			(layer "B.Fab")
			(hide yes)
			(effects
				(font
					(size 1 1)
					(thickness 0.15)
				)
				(justify mirror)
			)
		)
		(property "MPN" "CR0402-FX-1002GLF"
			(at 250 403.65 0)
			(layer "B.Fab")
			(hide yes)
			(effects
				(font
					(size 1 1)
					(thickness 0.15)
				)
				(justify mirror)
			)
		)
		(property "Manufacturer" "Bourns"
			(at 250 403.65 0)
			(layer "B.Fab")
			(hide yes)
			(effects
				(font
					(size 1 1)
					(thickness 0.15)
				)
				(justify mirror)
			)
		)
		(property "Tolerance" "1%"
			(at 250 403.65 0)
			(layer "B.Fab")
			(hide yes)
			(effects
				(font
					(size 1 1)
					(thickness 0.15)
				)
				(justify mirror)
			)
		)
		(property "Val" "10k"
			(at 250 403.65 0)
			(layer "B.Fab")
			(hide yes)
			(effects
				(font
					(size 1 1)
					(thickness 0.15)
				)
				(justify mirror)
			)
		)
		(sheetname "/PCIe connector/")
		(sheetfile "pcie-connector.kicad_sch")
		(attr exclude_from_pos_files exclude_from_bom dnp)
		(fp_rect
			(start -0.93 0.47)
			(end 0.93 -0.47)
			(stroke
				(width 0.05)
				(type solid)
			)
			(fill no)
			(layer "B.CrtYd")
		)
		(fp_rect
			(start -0.5 0.25)
			(end 0.5 -0.25)
			(stroke
				(width 0.15)
				(type solid)
			)
			(fill no)
			(layer "B.Fab")
		)
		(pad "1" smd roundrect
			(at -0.485 0 180)
			(size 0.59 0.64)
			(layers "B.Cu" "B.Mask" "B.Paste")
			(roundrect_rratio 0.25)
			(net 1 "GND")
			(pintype "passive")
		)
		(pad "2" smd roundrect
			(at 0.485 0 180)
			(size 0.59 0.64)
			(layers "B.Cu" "B.Mask" "B.Paste")
			(roundrect_rratio 0.25)
			(net 135 "PCIE.PWRGD")
			(pintype "passive")
		)
	)
	(footprint "antmicro-footprints:TP_SMD_1mm"
		(layer "B.Cu")
		(at 200.6 151.8 90)
		(property "Reference" "TP40"
			(at 0.5 -0.3 90)
			(layer "B.SilkS")
			(effects
				(font
					(size 0.7 0.7)
					(thickness 0.15)
				)
				(justify right top mirror)
			)
		)
		(property "Value" "TP_1mm_SMD"
			(at 0 -1.4 90)
			(layer "B.Fab")
			(effects
				(font
					(size 0.7 0.7)
					(thickness 0.15)
				)
				(justify right top mirror)
			)
		)
		(property "MPN" ""
			(at 0 0 270)
			(unlocked yes)
			(layer "B.Fab")
			(hide yes)
			(effects
				(font
					(size 1 1)
					(thickness 0.15)
				)
				(justify mirror)
			)
		)
		(property "Manufacturer" ""
			(at 0 0 270)
			(unlocked yes)
			(layer "B.Fab")
			(hide yes)
			(effects
				(font
					(size 1 1)
					(thickness 0.15)
				)
				(justify mirror)
			)
		)
		(property "Author" "Antmicro"
			(at 0 0 270)
			(unlocked yes)
			(layer "B.Fab")
			(hide yes)
			(effects
				(font
					(size 1 1)
					(thickness 0.15)
				)
				(justify mirror)
			)
		)
		(property "License" "Apache-2.0"
			(at 0 0 270)
			(unlocked yes)
			(layer "B.Fab")
			(hide yes)
			(effects
				(font
					(size 1 1)
					(thickness 0.15)
				)
				(justify mirror)
			)
		)
		(sheetname "/I^{2}C/")
		(sheetfile "i2c.kicad_sch")
		(attr exclude_from_pos_files)
		(fp_circle
			(center 0 0)
			(end 0.6 0)
			(stroke
				(width 0.05)
				(type default)
			)
			(fill no)
			(layer "B.CrtYd")
		)
		(fp_text user "${REFERENCE}"
			(at -0.5 -2.8 90)
			(layer "B.Fab")
			(effects
				(font
					(size 0.7 0.7)
					(thickness 0.15)
				)
				(justify right top mirror)
			)
		)
		(fp_text user "Author: Antmicro"
			(at -0.5 -4 90)
			(layer "B.Fab")
			(effects
				(font
					(size 0.7 0.7)
					(thickness 0.15)
				)
				(justify right top mirror)
			)
		)
		(fp_text user "License: Apache-2.0"
			(at -0.5 -5.2 90)
			(layer "B.Fab")
			(effects
				(font
					(size 0.7 0.7)
					(thickness 0.15)
				)
				(justify right top mirror)
			)
		)
		(pad "1" smd circle
			(at 0 0 90)
			(size 1 1)
			(layers "B.Cu" "B.Mask")
			(net 686 "IN1")
			(pinfunction "1")
			(pintype "passive")
		)
	)
)
